(kicad_pcb
	(version 20260206)
	(generator "pcbnew")
	(generator_version "10.0")
	(general
		(thickness 1.6)
		(legacy_teardrops no)
	)
	(paper "A4")
	(title_block
		(title "v2-pdb — ms_pdb_v2.brd")
		(comment 1 "Open CloudServer (Microsoft) / footprints 292-292 of 348")
	)
	(layers
		(0 "F.Cu" signal "TOP")
		(4 "In1.Cu" signal "GND")
		(6 "In2.Cu" signal "IN1")
		(8 "In3.Cu" signal "VCC")
		(10 "In4.Cu" signal "VCC1")
		(12 "In5.Cu" signal "IN2")
		(14 "In6.Cu" signal "GND1")
		(2 "B.Cu" signal "BOTTOM")
		(9 "F.Adhes" user "F.Adhesive")
		(11 "B.Adhes" user "B.Adhesive")
		(13 "F.Paste" user "Package Geometry/Pastemask Top")
		(15 "B.Paste" user "Package Geometry/Pastemask Bottom")
		(5 "F.SilkS" user "Ref Des/Silkscreen Top")
		(7 "B.SilkS" user "Ref Des/Silkscreen Bottom")
		(1 "F.Mask" user "Board Geometry/Soldermask Top")
		(3 "B.Mask" user "Board Geometry/Soldermask Bottom")
		(17 "Dwgs.User" user "User.Drawings")
		(19 "Cmts.User" user "User.Comments")
		(21 "Eco1.User" user "User.Eco1")
		(23 "Eco2.User" user "User.Eco2")
		(25 "Edge.Cuts" user "Board Geometry/Outline")
		(27 "Margin" user)
		(31 "F.CrtYd" user "Package Geometry/Place Bound Top")
		(29 "B.CrtYd" user "Package Geometry/Place Bound Bottom")
		(35 "F.Fab" user "Ref Des/Assembly Top")
		(33 "B.Fab" user "Ref Des/Assembly Bottom")
	)
	(footprint ""
		(layer "F.Cu")
		(at 27.640026 -462.229962 -90)
		(property "Reference" "R101"
			(at -1.561592 0.00381 90)
			(unlocked yes)
			(layer "F.SilkS")
			(effects
				(font
					(size 0.7874 0.5842)
					(thickness 0.1524)
				)
				(justify left)
			)
		)
		(property "Value" ""
			(at 0 0 270)
			(layer "F.Fab")
			(effects
				(font
					(size 1.27 1.27)
				)
			)
		)
		(duplicate_pad_numbers_are_jumpers no)
		(fp_line
			(start -0.7874 0.4064)
			(end -0.7874 -0.4064)
			(stroke
				(width 0.1524)
				(type default)
			)
			(layer "F.SilkS")
		)
		(fp_line
			(start 0.7874 0.4064)
			(end -0.7874 0.4064)
			(stroke
				(width 0.1524)
				(type default)
			)
			(layer "F.SilkS")
		)
		(fp_line
			(start -0.7874 -0.4064)
			(end 0.7874 -0.4064)
			(stroke
				(width 0.1524)
				(type default)
			)
			(layer "F.SilkS")
		)
		(fp_line
			(start 0.7874 -0.4064)
			(end 0.7874 0.4064)
			(stroke
				(width 0.1524)
				(type default)
			)
			(layer "F.SilkS")
		)
		(fp_poly
			(pts
				(xy -0.508 0.2794) (xy -0.508 0.2286) (xy -0.635 0.2286) (xy -0.635 -0.254) (xy -0.5334 -0.254)
				(xy -0.5334 -0.2794) (xy 0.5334 -0.2794) (xy 0.5334 -0.254) (xy 0.635 -0.254) (xy 0.635 0.254) (xy 0.5334 0.254)
				(xy 0.5334 0.2794)
			)
			(stroke
				(width 0)
				(type default)
			)
			(fill no)
			(layer "F.CrtYd")
		)
		(pad "1" smd rect
			(at 0.40005 0 270)
			(size 0.4572 0.508)
			(layers "F.Cu" "F.Mask" "F.Paste")
			(net "PSU6_REMOTE_N")
		)
		(pad "2" smd rect
			(at -0.40005 0 270)
			(size 0.4572 0.508)
			(layers "F.Cu" "F.Mask" "F.Paste")
			(net "PSU6_REMOTE_R_N")
		)
	)
)
